(kicad_pcb
	(version 20260206)
	(generator "pcbnew")
	(generator_version "10.0")
	(general
		(thickness 1.6)
		(legacy_teardrops no)
	)
	(paper "A4")
	(title_block
		(title "03242023_DA0F0TMBIJ0_F0T_Motherboard_J_brd_V01_OCP.brd")
		(comment 1 "Grand Teton / footprints 162-168 of 6105")
	)
	(layers
		(0 "F.Cu" signal "TOP")
		(4 "In1.Cu" signal "GND")
		(6 "In2.Cu" signal "IN1")
		(8 "In3.Cu" signal "GND1")
		(10 "In4.Cu" signal "IN2")
		(12 "In5.Cu" signal "GND2")
		(14 "In6.Cu" signal "IN3")
		(16 "In7.Cu" signal "GND3")
		(18 "In8.Cu" signal "VCC")
		(20 "In9.Cu" signal "VCC1")
		(22 "In10.Cu" signal "GND4")
		(24 "In11.Cu" signal "IN4")
		(26 "In12.Cu" signal "GND5")
		(28 "In13.Cu" signal "IN5")
		(30 "In14.Cu" signal "GND6")
		(32 "In15.Cu" signal "IN6")
		(34 "In16.Cu" signal "GND7")
		(2 "B.Cu" signal "BOTTOM")
		(9 "F.Adhes" user "F.Adhesive")
		(11 "B.Adhes" user "B.Adhesive")
		(13 "F.Paste" user "Package Geometry/Pastemask Top")
		(15 "B.Paste" user "Package Geometry/Pastemask Bottom")
		(5 "F.SilkS" user "Ref Des/Silkscreen Top")
		(7 "B.SilkS" user "Ref Des/Silkscreen Bottom")
		(1 "F.Mask" user "Board Geometry/Soldermask Top")
		(3 "B.Mask" user "Board Geometry/Soldermask Bottom")
		(17 "Dwgs.User" user "User.Drawings")
		(19 "Cmts.User" user "User.Comments")
		(21 "Eco1.User" user "User.Eco1")
		(23 "Eco2.User" user "User.Eco2")
		(25 "Edge.Cuts" user "Board Geometry/Outline")
		(27 "Margin" user)
		(31 "F.CrtYd" user "Package Geometry/Place Bound Top")
		(29 "B.CrtYd" user "Package Geometry/Place Bound Bottom")
		(35 "F.Fab" user "Ref Des/Assembly Top")
		(33 "B.Fab" user "Ref Des/Assembly Bottom")
	)
	(footprint ""
		(layer "F.Cu")
		(at 22.935438 -423.64152 -90)
		(property "Reference" "R3066"
			(at 0 0 270)
			(layer "F.SilkS")
			(hide yes)
			(effects
				(font
					(size 1.27 1.27)
				)
			)
		)
		(property "Value" ""
			(at 0 0 270)
			(layer "F.Fab")
			(effects
				(font
					(size 1.27 1.27)
				)
			)
		)
		(duplicate_pad_numbers_are_jumpers no)
		(fp_line
			(start -0.7874 0.4064)
			(end -0.7874 -0.4064)
			(stroke
				(width 0.1524)
				(type default)
			)
			(layer "F.SilkS")
		)
		(fp_line
			(start 0.7874 0.4064)
			(end -0.7874 0.4064)
			(stroke
				(width 0.1524)
				(type default)
			)
			(layer "F.SilkS")
		)
		(fp_line
			(start -0.7874 -0.4064)
			(end 0.7874 -0.4064)
			(stroke
				(width 0.1524)
				(type default)
			)
			(layer "F.SilkS")
		)
		(fp_line
			(start 0.7874 -0.4064)
			(end 0.7874 0.4064)
			(stroke
				(width 0.1524)
				(type default)
			)
			(layer "F.SilkS")
		)
		(fp_line
			(start -0.67945 0.3048)
			(end -0.67945 -0.305054)
			(stroke
				(width 0.1)
				(type default)
			)
			(layer "F.Fab")
		)
		(fp_line
			(start -0.12065 0.3048)
			(end -0.67945 0.3048)
			(stroke
				(width 0.1)
				(type default)
			)
			(layer "F.Fab")
		)
		(fp_line
			(start 0.120396 0.3048)
			(end 0.120396 0.2794)
			(stroke
				(width 0.1)
				(type default)
			)
			(layer "F.Fab")
		)
		(fp_line
			(start 0.67945 0.3048)
			(end 0.120396 0.3048)
			(stroke
				(width 0.1)
				(type default)
			)
			(layer "F.Fab")
		)
		(fp_line
			(start -0.12065 0.2794)
			(end -0.12065 0.3048)
			(stroke
				(width 0.1)
				(type default)
			)
			(layer "F.Fab")
		)
		(fp_line
			(start 0.120396 0.2794)
			(end -0.12065 0.2794)
			(stroke
				(width 0.1)
				(type default)
			)
			(layer "F.Fab")
		)
		(fp_line
			(start -0.12065 -0.2794)
			(end 0.12065 -0.2794)
			(stroke
				(width 0.1)
				(type default)
			)
			(layer "F.Fab")
		)
		(fp_line
			(start 0.12065 -0.2794)
			(end 0.12065 -0.3048)
			(stroke
				(width 0.1)
				(type default)
			)
			(layer "F.Fab")
		)
		(fp_line
			(start 0.12065 -0.3048)
			(end 0.67945 -0.3048)
			(stroke
				(width 0.1)
				(type default)
			)
			(layer "F.Fab")
		)
		(fp_line
			(start 0.67945 -0.3048)
			(end 0.67945 0.3048)
			(stroke
				(width 0.1)
				(type default)
			)
			(layer "F.Fab")
		)
		(fp_line
			(start -0.67945 -0.305054)
			(end -0.12065 -0.305054)
			(stroke
				(width 0.1)
				(type default)
			)
			(layer "F.Fab")
		)
		(fp_line
			(start -0.12065 -0.305054)
			(end -0.12065 -0.2794)
			(stroke
				(width 0.1)
				(type default)
			)
			(layer "F.Fab")
		)
		(pad "1" smd circle
			(at -0.40005 0 270)
			(size 0 0)
			(layers "F.Cu" "F.Mask" "F.Paste")
			(net "FM_SMB_1_ALERT_GPU_ISO_N")
		)
		(pad "2" smd circle
			(at 0.40005 0 270)
			(size 0 0)
			(layers "F.Cu" "F.Mask" "F.Paste")
			(net "FM_SMB_1_ALERT_GPU_ISO_R_N")
		)
	)
	(footprint ""
		(layer "F.Cu")
		(at 71.657718 -408.517344 -90)
		(property "Reference" "C695"
			(at 0 0 270)
			(layer "F.SilkS")
			(hide yes)
			(effects
				(font
					(size 1.27 1.27)
				)
			)
		)
		(property "Value" ""
			(at 0 0 270)
			(layer "F.Fab")
			(effects
				(font
					(size 1.27 1.27)
				)
			)
		)
		(duplicate_pad_numbers_are_jumpers no)
		(fp_line
			(start -0.299974 0.150114)
			(end -0.299974 -0.150114)
			(stroke
				(width 0.1)
				(type default)
			)
			(layer "F.Fab")
		)
		(fp_line
			(start 0.299974 0.150114)
			(end -0.299974 0.150114)
			(stroke
				(width 0.1)
				(type default)
			)
			(layer "F.Fab")
		)
		(fp_line
			(start -0.299974 -0.150114)
			(end 0.299974 -0.150114)
			(stroke
				(width 0.1)
				(type default)
			)
			(layer "F.Fab")
		)
		(fp_line
			(start 0.299974 -0.150114)
			(end 0.299974 0.150114)
			(stroke
				(width 0.1)
				(type default)
			)
			(layer "F.Fab")
		)
		(pad "1" smd rect
			(at -0.2667 0 270)
			(size 0.3048 0.381)
			(layers "F.Cu" "F.Mask" "F.Paste")
			(net "P5E_CPU1_PE4_TX_C_DP<7>")
		)
		(pad "2" smd rect
			(at 0.2667 0 270)
			(size 0.3048 0.381)
			(layers "F.Cu" "F.Mask" "F.Paste")
			(net "P5E_CPU1_PE4_TX_DP<7>")
		)
	)
	(footprint ""
		(layer "F.Cu")
		(at 201.00036 -112.994948 180)
		(property "Reference" "R4145"
			(at 0 0 180)
			(layer "F.SilkS")
			(hide yes)
			(effects
				(font
					(size 1.27 1.27)
				)
			)
		)
		(property "Value" ""
			(at 0 0 180)
			(layer "F.Fab")
			(effects
				(font
					(size 1.27 1.27)
				)
			)
		)
		(duplicate_pad_numbers_are_jumpers no)
		(fp_line
			(start 0.7874 0.4064)
			(end -0.7874 0.4064)
			(stroke
				(width 0.1524)
				(type default)
			)
			(layer "F.SilkS")
		)
		(fp_line
			(start 0.7874 -0.4064)
			(end 0.7874 0.4064)
			(stroke
				(width 0.1524)
				(type default)
			)
			(layer "F.SilkS")
		)
		(fp_line
			(start -0.7874 0.4064)
			(end -0.7874 -0.4064)
			(stroke
				(width 0.1524)
				(type default)
			)
			(layer "F.SilkS")
		)
		(fp_line
			(start -0.7874 -0.4064)
			(end 0.7874 -0.4064)
			(stroke
				(width 0.1524)
				(type default)
			)
			(layer "F.SilkS")
		)
		(fp_line
			(start 0.67945 0.3048)
			(end 0.120396 0.3048)
			(stroke
				(width 0.1)
				(type default)
			)
			(layer "F.Fab")
		)
		(fp_line
			(start 0.67945 -0.3048)
			(end 0.67945 0.3048)
			(stroke
				(width 0.1)
				(type default)
			)
			(layer "F.Fab")
		)
		(fp_line
			(start 0.12065 -0.2794)
			(end 0.12065 -0.3048)
			(stroke
				(width 0.1)
				(type default)
			)
			(layer "F.Fab")
		)
		(fp_line
			(start 0.12065 -0.3048)
			(end 0.67945 -0.3048)
			(stroke
				(width 0.1)
				(type default)
			)
			(layer "F.Fab")
		)
		(fp_line
			(start 0.120396 0.3048)
			(end 0.120396 0.2794)
			(stroke
				(width 0.1)
				(type default)
			)
			(layer "F.Fab")
		)
		(fp_line
			(start 0.120396 0.2794)
			(end -0.12065 0.2794)
			(stroke
				(width 0.1)
				(type default)
			)
			(layer "F.Fab")
		)
		(fp_line
			(start -0.12065 0.3048)
			(end -0.67945 0.3048)
			(stroke
				(width 0.1)
				(type default)
			)
			(layer "F.Fab")
		)
		(fp_line
			(start -0.12065 0.2794)
			(end -0.12065 0.3048)
			(stroke
				(width 0.1)
				(type default)
			)
			(layer "F.Fab")
		)
		(fp_line
			(start -0.12065 -0.2794)
			(end 0.12065 -0.2794)
			(stroke
				(width 0.1)
				(type default)
			)
			(layer "F.Fab")
		)
		(fp_line
			(start -0.12065 -0.305054)
			(end -0.12065 -0.2794)
			(stroke
				(width 0.1)
				(type default)
			)
			(layer "F.Fab")
		)
		(fp_line
			(start -0.67945 0.3048)
			(end -0.67945 -0.305054)
			(stroke
				(width 0.1)
				(type default)
			)
			(layer "F.Fab")
		)
		(fp_line
			(start -0.67945 -0.305054)
			(end -0.12065 -0.305054)
			(stroke
				(width 0.1)
				(type default)
			)
			(layer "F.Fab")
		)
		(pad "1" smd circle
			(at -0.40005 0 180)
			(size 0 0)
			(layers "F.Cu" "F.Mask" "F.Paste")
			(net "PRSNT_CABLE_GPU_B3_ISO_N")
		)
		(pad "2" smd circle
			(at 0.40005 0 180)
			(size 0 0)
			(layers "F.Cu" "F.Mask" "F.Paste")
			(net "PRSNT_CABLE_GPU_B3_ISO_R_N")
		)
	)
	(footprint ""
		(layer "F.Cu")
		(at 193.004186 -429.41113 90)
		(property "Reference" "R2946"
			(at 0 0 90)
			(layer "F.SilkS")
			(hide yes)
			(effects
				(font
					(size 1.27 1.27)
				)
			)
		)
		(property "Value" ""
			(at 0 0 90)
			(layer "F.Fab")
			(effects
				(font
					(size 1.27 1.27)
				)
			)
		)
		(duplicate_pad_numbers_are_jumpers no)
		(fp_line
			(start 0.7874 -0.4064)
			(end 0.7874 0.4064)
			(stroke
				(width 0.1524)
				(type default)
			)
			(layer "F.SilkS")
		)
		(fp_line
			(start -0.7874 -0.4064)
			(end 0.7874 -0.4064)
			(stroke
				(width 0.1524)
				(type default)
			)
			(layer "F.SilkS")
		)
		(fp_line
			(start 0.7874 0.4064)
			(end -0.7874 0.4064)
			(stroke
				(width 0.1524)
				(type default)
			)
			(layer "F.SilkS")
		)
		(fp_line
			(start -0.7874 0.4064)
			(end -0.7874 -0.4064)
			(stroke
				(width 0.1524)
				(type default)
			)
			(layer "F.SilkS")
		)
		(fp_line
			(start -0.12065 -0.305054)
			(end -0.12065 -0.2794)
			(stroke
				(width 0.1)
				(type default)
			)
			(layer "F.Fab")
		)
		(fp_line
			(start -0.67945 -0.305054)
			(end -0.12065 -0.305054)
			(stroke
				(width 0.1)
				(type default)
			)
			(layer "F.Fab")
		)
		(fp_line
			(start 0.67945 -0.3048)
			(end 0.67945 0.3048)
			(stroke
				(width 0.1)
				(type default)
			)
			(layer "F.Fab")
		)
		(fp_line
			(start 0.12065 -0.3048)
			(end 0.67945 -0.3048)
			(stroke
				(width 0.1)
				(type default)
			)
			(layer "F.Fab")
		)
		(fp_line
			(start 0.12065 -0.2794)
			(end 0.12065 -0.3048)
			(stroke
				(width 0.1)
				(type default)
			)
			(layer "F.Fab")
		)
		(fp_line
			(start -0.12065 -0.2794)
			(end 0.12065 -0.2794)
			(stroke
				(width 0.1)
				(type default)
			)
			(layer "F.Fab")
		)
		(fp_line
			(start 0.120396 0.2794)
			(end -0.12065 0.2794)
			(stroke
				(width 0.1)
				(type default)
			)
			(layer "F.Fab")
		)
		(fp_line
			(start -0.12065 0.2794)
			(end -0.12065 0.3048)
			(stroke
				(width 0.1)
				(type default)
			)
			(layer "F.Fab")
		)
		(fp_line
			(start 0.67945 0.3048)
			(end 0.120396 0.3048)
			(stroke
				(width 0.1)
				(type default)
			)
			(layer "F.Fab")
		)
		(fp_line
			(start 0.120396 0.3048)
			(end 0.120396 0.2794)
			(stroke
				(width 0.1)
				(type default)
			)
			(layer "F.Fab")
		)
		(fp_line
			(start -0.12065 0.3048)
			(end -0.67945 0.3048)
			(stroke
				(width 0.1)
				(type default)
			)
			(layer "F.Fab")
		)
		(fp_line
			(start -0.67945 0.3048)
			(end -0.67945 -0.305054)
			(stroke
				(width 0.1)
				(type default)
			)
			(layer "F.Fab")
		)
		(pad "1" smd circle
			(at -0.40005 0 90)
			(size 0 0)
			(layers "F.Cu" "F.Mask" "F.Paste")
			(net "P3V3_AUX")
		)
		(pad "2" smd circle
			(at 0.40005 0 90)
			(size 0 0)
			(layers "F.Cu" "F.Mask" "F.Paste")
			(net "FM_GPU_HSC_EN_BUF_R")
		)
	)
	(footprint ""
		(layer "F.Cu")
		(at 133.27888 -106.898948)
		(property "Reference" "R4410"
			(at 0 0 0)
			(layer "F.SilkS")
			(hide yes)
			(effects
				(font
					(size 1.27 1.27)
				)
			)
		)
		(property "Value" ""
			(at 0 0 0)
			(layer "F.Fab")
			(effects
				(font
					(size 1.27 1.27)
				)
			)
		)
		(duplicate_pad_numbers_are_jumpers no)
		(fp_line
			(start -0.7874 -0.4064)
			(end 0.7874 -0.4064)
			(stroke
				(width 0.1524)
				(type default)
			)
			(layer "F.SilkS")
		)
		(fp_line
			(start -0.7874 0.4064)
			(end -0.7874 -0.4064)
			(stroke
				(width 0.1524)
				(type default)
			)
			(layer "F.SilkS")
		)
		(fp_line
			(start 0.7874 -0.4064)
			(end 0.7874 0.4064)
			(stroke
				(width 0.1524)
				(type default)
			)
			(layer "F.SilkS")
		)
		(fp_line
			(start 0.7874 0.4064)
			(end -0.7874 0.4064)
			(stroke
				(width 0.1524)
				(type default)
			)
			(layer "F.SilkS")
		)
		(fp_line
			(start -0.67945 -0.305054)
			(end -0.12065 -0.305054)
			(stroke
				(width 0.1)
				(type default)
			)
			(layer "F.Fab")
		)
		(fp_line
			(start -0.67945 0.3048)
			(end -0.67945 -0.305054)
			(stroke
				(width 0.1)
				(type default)
			)
			(layer "F.Fab")
		)
		(fp_line
			(start -0.12065 -0.305054)
			(end -0.12065 -0.2794)
			(stroke
				(width 0.1)
				(type default)
			)
			(layer "F.Fab")
		)
		(fp_line
			(start -0.12065 -0.2794)
			(end 0.12065 -0.2794)
			(stroke
				(width 0.1)
				(type default)
			)
			(layer "F.Fab")
		)
		(fp_line
			(start -0.12065 0.2794)
			(end -0.12065 0.3048)
			(stroke
				(width 0.1)
				(type default)
			)
			(layer "F.Fab")
		)
		(fp_line
			(start -0.12065 0.3048)
			(end -0.67945 0.3048)
			(stroke
				(width 0.1)
				(type default)
			)
			(layer "F.Fab")
		)
		(fp_line
			(start 0.120396 0.2794)
			(end -0.12065 0.2794)
			(stroke
				(width 0.1)
				(type default)
			)
			(layer "F.Fab")
		)
		(fp_line
			(start 0.120396 0.3048)
			(end 0.120396 0.2794)
			(stroke
				(width 0.1)
				(type default)
			)
			(layer "F.Fab")
		)
		(fp_line
			(start 0.12065 -0.3048)
			(end 0.67945 -0.3048)
			(stroke
				(width 0.1)
				(type default)
			)
			(layer "F.Fab")
		)
		(fp_line
			(start 0.12065 -0.2794)
			(end 0.12065 -0.3048)
			(stroke
				(width 0.1)
				(type default)
			)
			(layer "F.Fab")
		)
		(fp_line
			(start 0.67945 -0.3048)
			(end 0.67945 0.3048)
			(stroke
				(width 0.1)
				(type default)
			)
			(layer "F.Fab")
		)
		(fp_line
			(start 0.67945 0.3048)
			(end 0.120396 0.3048)
			(stroke
				(width 0.1)
				(type default)
			)
			(layer "F.Fab")
		)
		(pad "1" smd circle
			(at -0.40005 0)
			(size 0 0)
			(layers "F.Cu" "F.Mask" "F.Paste")
			(net "H_CPU1_MEMTRIP")
		)
		(pad "2" smd circle
			(at 0.40005 0)
			(size 0 0)
			(layers "F.Cu" "F.Mask" "F.Paste")
			(net "H_CPU1_MEMTRIP_R")
		)
	)
	(footprint ""
		(layer "F.Cu")
		(at 179.058062 -32.935672 90)
		(property "Reference" "PC2229"
			(at 0 0 90)
			(layer "F.SilkS")
			(hide yes)
			(effects
				(font
					(size 1.27 1.27)
				)
			)
		)
		(property "Value" ""
			(at 0 0 90)
			(layer "F.Fab")
			(effects
				(font
					(size 1.27 1.27)
				)
			)
		)
		(duplicate_pad_numbers_are_jumpers no)
		(fp_line
			(start 0.7874 -0.4064)
			(end 0.7874 0.4064)
			(stroke
				(width 0.1524)
				(type default)
			)
			(layer "F.SilkS")
		)
		(fp_line
			(start -0.7874 -0.4064)
			(end 0.7874 -0.4064)
			(stroke
				(width 0.1524)
				(type default)
			)
			(layer "F.SilkS")
		)
		(fp_line
			(start 0.7874 0.4064)
			(end -0.7874 0.4064)
			(stroke
				(width 0.1524)
				(type default)
			)
			(layer "F.SilkS")
		)
		(fp_line
			(start -0.7874 0.4064)
			(end -0.7874 -0.4064)
			(stroke
				(width 0.1524)
				(type default)
			)
			(layer "F.SilkS")
		)
		(fp_line
			(start -0.12065 -0.305054)
			(end -0.12065 -0.2794)
			(stroke
				(width 0.1)
				(type default)
			)
			(layer "F.Fab")
		)
		(fp_line
			(start -0.67945 -0.305054)
			(end -0.12065 -0.305054)
			(stroke
				(width 0.1)
				(type default)
			)
			(layer "F.Fab")
		)
		(fp_line
			(start 0.67945 -0.3048)
			(end 0.67945 0.3048)
			(stroke
				(width 0.1)
				(type default)
			)
			(layer "F.Fab")
		)
		(fp_line
			(start 0.12065 -0.3048)
			(end 0.67945 -0.3048)
			(stroke
				(width 0.1)
				(type default)
			)
			(layer "F.Fab")
		)
		(fp_line
			(start 0.12065 -0.2794)
			(end 0.12065 -0.3048)
			(stroke
				(width 0.1)
				(type default)
			)
			(layer "F.Fab")
		)
		(fp_line
			(start -0.12065 -0.2794)
			(end 0.12065 -0.2794)
			(stroke
				(width 0.1)
				(type default)
			)
			(layer "F.Fab")
		)
		(fp_line
			(start 0.120396 0.2794)
			(end -0.12065 0.2794)
			(stroke
				(width 0.1)
				(type default)
			)
			(layer "F.Fab")
		)
		(fp_line
			(start -0.12065 0.2794)
			(end -0.12065 0.3048)
			(stroke
				(width 0.1)
				(type default)
			)
			(layer "F.Fab")
		)
		(fp_line
			(start 0.67945 0.3048)
			(end 0.120396 0.3048)
			(stroke
				(width 0.1)
				(type default)
			)
			(layer "F.Fab")
		)
		(fp_line
			(start 0.120396 0.3048)
			(end 0.120396 0.2794)
			(stroke
				(width 0.1)
				(type default)
			)
			(layer "F.Fab")
		)
		(fp_line
			(start -0.12065 0.3048)
			(end -0.67945 0.3048)
			(stroke
				(width 0.1)
				(type default)
			)
			(layer "F.Fab")
		)
		(fp_line
			(start -0.67945 0.3048)
			(end -0.67945 -0.305054)
			(stroke
				(width 0.1)
				(type default)
			)
			(layer "F.Fab")
		)
		(pad "1" smd circle
			(at -0.40005 0 90)
			(size 0 0)
			(layers "F.Cu" "F.Mask" "F.Paste")
			(net "P12V_SCM_TIMER")
		)
		(pad "2" smd circle
			(at 0.40005 0 90)
			(size 0 0)
			(layers "F.Cu" "F.Mask" "F.Paste")
			(net "GND")
		)
	)
	(footprint ""
		(layer "F.Cu")
		(at 418.69233 -408.517344 -90)
		(property "Reference" "C901"
			(at 0 0 270)
			(layer "F.SilkS")
			(hide yes)
			(effects
				(font
					(size 1.27 1.27)
				)
			)
		)
		(property "Value" ""
			(at 0 0 270)
			(layer "F.Fab")
			(effects
				(font
					(size 1.27 1.27)
				)
			)
		)
		(duplicate_pad_numbers_are_jumpers no)
		(fp_line
			(start -0.299974 0.150114)
			(end -0.299974 -0.150114)
			(stroke
				(width 0.1)
				(type default)
			)
			(layer "F.Fab")
		)
		(fp_line
			(start 0.299974 0.150114)
			(end -0.299974 0.150114)
			(stroke
				(width 0.1)
				(type default)
			)
			(layer "F.Fab")
		)
		(fp_line
			(start -0.299974 -0.150114)
			(end 0.299974 -0.150114)
			(stroke
				(width 0.1)
				(type default)
			)
			(layer "F.Fab")
		)
		(fp_line
			(start 0.299974 -0.150114)
			(end 0.299974 0.150114)
			(stroke
				(width 0.1)
				(type default)
			)
			(layer "F.Fab")
		)
		(pad "1" smd rect
			(at -0.2667 0 270)
			(size 0.3048 0.381)
			(layers "F.Cu" "F.Mask" "F.Paste")
			(net "P5E_CPU0_PE3_TX_C_DP<0>")
		)
		(pad "2" smd rect
			(at 0.2667 0 270)
			(size 0.3048 0.381)
			(layers "F.Cu" "F.Mask" "F.Paste")
			(net "P5E_CPU0_PE3_TX_DP<0>")
		)
	)
)
